FILE_TYPE = MULTI_PHYS_TABLE;
PART 'RT9059'
{=========================================================================================================================================================================}
:PACK_TYPE|MATERIAL  |PART_NUMBER      = EnvComp |PART_NUMBER   |JEDEC_TYPE       |DESCRIPTION                   |CLASS  |COMPONENT_TYPE  |HEIGHT      |LPID    | SPEED_URL | Status |RPL| AML | Bus_Unit | Days;
{=========================================================================================================================================================================}
'DFN'     | 'IC'     | 'H65765-001'(!) = ''      | 'H65765-001' | 'DFN10_12_50MF' | 'IC,LIN,DFN,RT9059,VREG W/E' | 'IC'  | 'LCC'          | '0.031 IN' | '3373' | 'http://speed.intel.com:8081/speed/module/pdm/item/pdm_item_detail_direct.asp?item_cde=H65765-001&item_rev=01&url_param=unused' | '' | '' | '' | '' | '' 
'DFN'     | 'EMPTY'  | 'H65765-001'(!) = ''      | 'H65765-001' | 'DFN10_12_50MF' | 'IC,LIN,DFN,RT9059,VREG W/E' | 'IO'  | 'LCC'          | '0.031 IN' | '3373' | 'http://speed.intel.com:8081/speed/module/pdm/item/pdm_item_detail_direct.asp?item_cde=H65765-001&item_rev=01&url_param=unused' | '' | '' | '' | '' | '' 
END_PART
END.
